# T6G (Grand Teton) — schematic netlist excerpt (pin names and nets, part order shuffled) for the footprints in the layout excerpt that follows; sources: Cadence DE-HDL packaged netlist, KiCad conversion of 04192023_DAF0TMB3IC0_F0TG_MB_C_brd_V02_OCP.brd

U99  SN74LVC1G07DBVR  EMPTY  pkg SMLF  page 171
  NC  = NC
  A  = FW_RECOVERY_R
  GND  = GND
  Y  = SCM_JTAG_MUX_S1
  VCC  = P3V3_AUX

R1334  Q_RES  0 5% EMPTY  pkg 0402LF  page 159 : A = I3C_SPD_DDRAF_CPU1_BYPASS_SCL ; B = I3C_SPD_DDRAF_CPU1_SCL

(kicad_pcb
	(version 20260206)
	(generator "pcbnew")
	(generator_version "10.0")
	(general
		(thickness 1.6)
		(legacy_teardrops no)
	)
	(paper "A4")
	(title_block
		(title "04192023_DAF0TMB3IC0_F0TG_MB_C_brd_V02_OCP.brd")
		(comment 1 "Grand Teton / footprints 2641-2642 of 8354")
	)
	(layers
		(0 "F.Cu" signal "TOP")
		(4 "In1.Cu" signal "GND")
		(6 "In2.Cu" signal "IN1")
		(8 "In3.Cu" signal "GND1")
		(10 "In4.Cu" signal "IN2")
		(12 "In5.Cu" signal "GND2")
		(14 "In6.Cu" signal "IN3")
		(16 "In7.Cu" signal "GND3")
		(18 "In8.Cu" signal "VCC")
		(20 "In9.Cu" signal "VCC1")
		(22 "In10.Cu" signal "GND4")
		(24 "In11.Cu" signal "IN4")
		(26 "In12.Cu" signal "GND5")
		(28 "In13.Cu" signal "IN5")
		(30 "In14.Cu" signal "GND6")
		(32 "In15.Cu" signal "IN6")
		(34 "In16.Cu" signal "GND7")
		(2 "B.Cu" signal "BOTTOM")
		(9 "F.Adhes" user "F.Adhesive")
		(11 "B.Adhes" user "B.Adhesive")
		(13 "F.Paste" user "Package Geometry/Pastemask Top")
		(15 "B.Paste" user "Package Geometry/Pastemask Bottom")
		(5 "F.SilkS" user "Ref Des/Silkscreen Top")
		(7 "B.SilkS" user "Ref Des/Silkscreen Bottom")
		(1 "F.Mask" user "Board Geometry/Soldermask Top")
		(3 "B.Mask" user "Board Geometry/Soldermask Bottom")
		(17 "Dwgs.User" user "User.Drawings")
		(19 "Cmts.User" user "User.Comments")
		(21 "Eco1.User" user "User.Eco1")
		(23 "Eco2.User" user "User.Eco2")
		(25 "Edge.Cuts" user "Board Geometry/Outline")
		(27 "Margin" user)
		(31 "F.CrtYd" user "Package Geometry/Place Bound Top")
		(29 "B.CrtYd" user "Package Geometry/Place Bound Bottom")
		(35 "F.Fab" user "Ref Des/Assembly Top")
		(33 "B.Fab" user "Ref Des/Assembly Bottom")
	)
	(footprint ""
		(layer "F.Cu")
		(at 33.865058 -170.50766)
		(property "Reference" "R1334"
			(at 0 0 0)
			(layer "F.SilkS")
			(hide yes)
			(effects
				(font
					(size 1.27 1.27)
				)
			)
		)
		(property "Value" ""
			(at 0 0 0)
			(layer "F.Fab")
			(effects
				(font
					(size 1.27 1.27)
				)
			)
		)
		(duplicate_pad_numbers_are_jumpers no)
		(fp_line
			(start -0.7874 -0.4064)
			(end 0.7874 -0.4064)
			(stroke
				(width 0.1524)
				(type default)
			)
			(layer "F.SilkS")
		)
		(fp_line
			(start -0.7874 0.4064)
			(end -0.7874 -0.4064)
			(stroke
				(width 0.1524)
				(type default)
			)
			(layer "F.SilkS")
		)
		(fp_line
			(start 0.7874 -0.4064)
			(end 0.7874 0.4064)
			(stroke
				(width 0.1524)
				(type default)
			)
			(layer "F.SilkS")
		)
		(fp_line
			(start 0.7874 0.4064)
			(end -0.7874 0.4064)
			(stroke
				(width 0.1524)
				(type default)
			)
			(layer "F.SilkS")
		)
		(fp_line
			(start -0.67945 -0.305054)
			(end -0.12065 -0.305054)
			(stroke
				(width 0.1)
				(type default)
			)
			(layer "F.Fab")
		)
		(fp_line
			(start -0.67945 0.3048)
			(end -0.67945 -0.305054)
			(stroke
				(width 0.1)
				(type default)
			)
			(layer "F.Fab")
		)
		(fp_line
			(start -0.12065 -0.305054)
			(end -0.12065 -0.2794)
			(stroke
				(width 0.1)
				(type default)
			)
			(layer "F.Fab")
		)
		(fp_line
			(start -0.12065 -0.2794)
			(end 0.12065 -0.2794)
			(stroke
				(width 0.1)
				(type default)
			)
			(layer "F.Fab")
		)
		(fp_line
			(start -0.12065 0.2794)
			(end -0.12065 0.3048)
			(stroke
				(width 0.1)
				(type default)
			)
			(layer "F.Fab")
		)
		(fp_line
			(start -0.12065 0.3048)
			(end -0.67945 0.3048)
			(stroke
				(width 0.1)
				(type default)
			)
			(layer "F.Fab")
		)
		(fp_line
			(start 0.120396 0.2794)
			(end -0.12065 0.2794)
			(stroke
				(width 0.1)
				(type default)
			)
			(layer "F.Fab")
		)
		(fp_line
			(start 0.120396 0.3048)
			(end 0.120396 0.2794)
			(stroke
				(width 0.1)
				(type default)
			)
			(layer "F.Fab")
		)
		(fp_line
			(start 0.12065 -0.3048)
			(end 0.67945 -0.3048)
			(stroke
				(width 0.1)
				(type default)
			)
			(layer "F.Fab")
		)
		(fp_line
			(start 0.12065 -0.2794)
			(end 0.12065 -0.3048)
			(stroke
				(width 0.1)
				(type default)
			)
			(layer "F.Fab")
		)
		(fp_line
			(start 0.67945 -0.3048)
			(end 0.67945 0.3048)
			(stroke
				(width 0.1)
				(type default)
			)
			(layer "F.Fab")
		)
		(fp_line
			(start 0.67945 0.3048)
			(end 0.120396 0.3048)
			(stroke
				(width 0.1)
				(type default)
			)
			(layer "F.Fab")
		)
		(pad "1" smd rect
			(at -0.40005 0 180)
			(size 0.4572 0.508)
			(layers "F.Cu" "F.Mask" "F.Paste")
			(net "I3C_SPD_DDRAF_CPU1_BYPASS_SCL")
		)
		(pad "2" smd rect
			(at 0.40005 0 180)
			(size 0.4572 0.508)
			(layers "F.Cu" "F.Mask" "F.Paste")
			(net "I3C_SPD_DDRAF_CPU1_SCL")
		)
	)
	(footprint ""
		(layer "F.Cu")
		(at 315.399928 -23.92934)
		(property "Reference" "U99"
			(at -2.032 -2.377948 0)
			(unlocked yes)
			(layer "F.SilkS")
			(effects
				(font
					(size 0.7874 0.5842)
					(thickness 0.1524)
				)
				(justify left)
			)
		)
		(property "Value" ""
			(at 0 0 0)
			(layer "F.Fab")
			(effects
				(font
					(size 1.27 1.27)
				)
			)
		)
		(duplicate_pad_numbers_are_jumpers no)
		(fp_line
			(start -2.0574 -1.651)
			(end -0.381 -1.651)
			(stroke
				(width 0.1524)
				(type default)
			)
			(layer "F.SilkS")
		)
		(fp_line
			(start -2.0574 1.651)
			(end -2.0574 -1.651)
			(stroke
				(width 0.1524)
				(type default)
			)
			(layer "F.SilkS")
		)
		(fp_line
			(start -0.381 -1.651)
			(end 0 -1.016)
			(stroke
				(width 0.1524)
				(type default)
			)
			(layer "F.SilkS")
		)
		(fp_line
			(start 0 -1.016)
			(end 0.381 -1.651)
			(stroke
				(width 0.1524)
				(type default)
			)
			(layer "F.SilkS")
		)
		(fp_line
			(start 0.381 -1.651)
			(end 2.0574 -1.651)
			(stroke
				(width 0.1524)
				(type default)
			)
			(layer "F.SilkS")
		)
		(fp_line
			(start 2.0574 -1.651)
			(end 2.0574 1.651)
			(stroke
				(width 0.1524)
				(type default)
			)
			(layer "F.SilkS")
		)
		(fp_line
			(start 2.0574 1.651)
			(end -2.0574 1.651)
			(stroke
				(width 0.1524)
				(type default)
			)
			(layer "F.SilkS")
		)
		(fp_poly
			(pts
				(xy -2.159 -1.016) (xy -2.71272 -0.719328) (xy -2.71272 -1.344168)
			)
			(stroke
				(width 0)
				(type default)
			)
			(fill yes)
			(layer "F.SilkS")
		)
		(fp_line
			(start -1.599946 -1.199896)
			(end -0.899922 -1.199896)
			(stroke
				(width 0.1)
				(type default)
			)
			(layer "F.Fab")
		)
		(fp_line
			(start -1.599946 1.199896)
			(end -1.599946 -1.199896)
			(stroke
				(width 0.1)
				(type default)
			)
			(layer "F.Fab")
		)
		(fp_line
			(start -0.899922 -1.549908)
			(end 0.899922 -1.549908)
			(stroke
				(width 0.1)
				(type default)
			)
			(layer "F.Fab")
		)
		(fp_line
			(start -0.899922 -1.199896)
			(end -0.899922 -1.549908)
			(stroke
				(width 0.1)
				(type default)
			)
			(layer "F.Fab")
		)
		(fp_line
			(start -0.899922 1.199896)
			(end -1.599946 1.199896)
			(stroke
				(width 0.1)
				(type default)
			)
			(layer "F.Fab")
		)
		(fp_line
			(start -0.899922 1.549908)
			(end -0.899922 1.199896)
			(stroke
				(width 0.1)
				(type default)
			)
			(layer "F.Fab")
		)
		(fp_line
			(start 0.899922 -1.549908)
			(end 0.899922 -1.199896)
			(stroke
				(width 0.1)
				(type default)
			)
			(layer "F.Fab")
		)
		(fp_line
			(start 0.899922 -1.199896)
			(end 1.599946 -1.199896)
			(stroke
				(width 0.1)
				(type default)
			)
			(layer "F.Fab")
		)
		(fp_line
			(start 0.899922 1.199896)
			(end 0.899922 1.549908)
			(stroke
				(width 0.1)
				(type default)
			)
			(layer "F.Fab")
		)
		(fp_line
			(start 0.899922 1.549908)
			(end -0.899922 1.549908)
			(stroke
				(width 0.1)
				(type default)
			)
			(layer "F.Fab")
		)
		(fp_line
			(start 1.599946 -1.199896)
			(end 1.599946 1.199896)
			(stroke
				(width 0.1)
				(type default)
			)
			(layer "F.Fab")
		)
		(fp_line
			(start 1.599946 1.199896)
			(end 0.899922 1.199896)
			(stroke
				(width 0.1)
				(type default)
			)
			(layer "F.Fab")
		)
		(fp_poly
			(pts
				(xy -2.71272 -0.719328) (xy -2.71272 -1.344168) (xy -2.159 -1.016)
			)
			(stroke
				(width 0)
				(type default)
			)
			(fill yes)
			(layer "F.Fab")
		)
		(pad "1" smd rect
			(at -1.225042 -0.94996 270)
			(size 0.5588 1.3462)
			(layers "F.Cu" "F.Mask" "F.Paste")
			(net "Net_10727")
		)
		(pad "2" smd rect
			(at -1.225042 0 270)
			(size 0.5588 1.3462)
			(layers "F.Cu" "F.Mask" "F.Paste")
			(net "FW_RECOVERY_R")
		)
		(pad "3" smd rect
			(at -1.225042 0.94996 270)
			(size 0.5588 1.3462)
			(layers "F.Cu" "F.Mask" "F.Paste")
			(net "GND")
		)
		(pad "4" smd rect
			(at 1.225042 0.94996 270)
			(size 0.5588 1.3462)
			(layers "F.Cu" "F.Mask" "F.Paste")
			(net "SCM_JTAG_MUX_S1")
		)
		(pad "5" smd rect
			(at 1.225042 -0.94996 270)
			(size 0.5588 1.3462)
			(layers "F.Cu" "F.Mask" "F.Paste")
			(net "P3V3_AUX")
		)
	)
)
